(kicad_pcb
	(version 20241229)
	(generator "pcbnew")
	(generator_version "9.0")
	(general
		(thickness 1.61)
		(legacy_teardrops no)
	)
	(paper "A3")
	(title_block
		(title "RDIMM DDR5 Tester")
		(date "2026-05-21")
		(rev "2.2.0")
		(company "Antmicro")
		(comment 9 "footprints 575-579 of 796")
	)
	(layers
		(0 "F.Cu" signal)
		(4 "In1.Cu" power)
		(6 "In2.Cu" mixed)
		(8 "In3.Cu" power)
		(10 "In4.Cu" mixed)
		(12 "In5.Cu" power)
		(14 "In6.Cu" mixed)
		(16 "In7.Cu" power)
		(18 "In8.Cu" power)
		(20 "In9.Cu" mixed)
		(22 "In10.Cu" power)
		(2 "B.Cu" signal)
		(9 "F.Adhes" user "F.Adhesive")
		(11 "B.Adhes" user "B.Adhesive")
		(13 "F.Paste" user)
		(15 "B.Paste" user)
		(5 "F.SilkS" user "F.Silkscreen")
		(7 "B.SilkS" user "B.Silkscreen")
		(1 "F.Mask" user)
		(3 "B.Mask" user)
		(17 "Dwgs.User" user "User.Drawings")
		(19 "Cmts.User" user "User.Comments")
		(21 "Eco1.User" user "User.Eco1")
		(23 "Eco2.User" user "User.Eco2")
		(25 "Edge.Cuts" user)
		(27 "Margin" user)
		(31 "F.CrtYd" user "F.Courtyard")
		(29 "B.CrtYd" user "B.Courtyard")
		(35 "F.Fab" user)
		(33 "B.Fab" user)
	)
	(footprint "antmicro-footprints:C_0402_1005Metric"
		(layer "B.Cu")
		(at 221.9 179.775 90)
		(descr "Capacitor SMD 0402")
		(tags "capacitor SMD 0402")
		(property "Reference" "C264"
			(at -2.2 -0.725 90)
			(layer "B.SilkS")
			(effects
				(font
					(size 0.7 0.7)
					(thickness 0.15)
				)
				(justify right bottom mirror)
			)
		)
		(property "Value" "C_22p_0402"
			(at -1.022927 -2.155213 90)
			(layer "B.Fab")
			(effects
				(font
					(size 0.7 0.7)
					(thickness 0.15)
				)
				(justify right bottom mirror)
			)
		)
		(property "Datasheet" "https://www.yageo.com/en/Chart/Download/pdf/CC0402JRNPO9BN220"
			(at 0 0 90)
			(layer "F.Fab")
			(hide yes)
			(effects
				(font
					(size 1.27 1.27)
					(thickness 0.15)
				)
			)
		)
		(property "Description" "SMD Multilayer Ceramic Capacitor, 22 pF, 50 V, 0402 [1005 Metric], ± 5%, C0G / NP0, CC Series"
			(at 0 0 90)
			(layer "F.Fab")
			(hide yes)
			(effects
				(font
					(size 1.27 1.27)
					(thickness 0.15)
				)
			)
		)
		(property "MPN" "CC0402JRNPO9BN220"
			(at 0 0 90)
			(unlocked yes)
			(layer "B.Fab")
			(hide yes)
			(effects
				(font
					(size 1 1)
					(thickness 0.15)
				)
				(justify mirror)
			)
		)
		(property "Manufacturer" "YAGEO"
			(at 0 0 90)
			(unlocked yes)
			(layer "B.Fab")
			(hide yes)
			(effects
				(font
					(size 1 1)
					(thickness 0.15)
				)
				(justify mirror)
			)
		)
		(property "License" "Apache-2.0"
			(at 0 0 90)
			(unlocked yes)
			(layer "B.Fab")
			(hide yes)
			(effects
				(font
					(size 1 1)
					(thickness 0.15)
				)
				(justify mirror)
			)
		)
		(property "Author" "Antmicro"
			(at 0 0 90)
			(unlocked yes)
			(layer "B.Fab")
			(hide yes)
			(effects
				(font
					(size 1 1)
					(thickness 0.15)
				)
				(justify mirror)
			)
		)
		(property "Val" "22p"
			(at 0 0 90)
			(unlocked yes)
			(layer "B.Fab")
			(hide yes)
			(effects
				(font
					(size 1 1)
					(thickness 0.15)
				)
				(justify mirror)
			)
		)
		(property "Voltage" ""
			(at 0 0 90)
			(unlocked yes)
			(layer "B.Fab")
			(hide yes)
			(effects
				(font
					(size 1 1)
					(thickness 0.15)
				)
				(justify mirror)
			)
		)
		(property "Dielectric" ""
			(at 0 0 90)
			(unlocked yes)
			(layer "B.Fab")
			(hide yes)
			(effects
				(font
					(size 1 1)
					(thickness 0.15)
				)
				(justify mirror)
			)
		)
		(sheetname "/Supply/DC-DC VCCINT/")
		(sheetfile "dc-dc-vccint.kicad_sch")
		(attr smd)
		(fp_rect
			(start -0.925 0.47)
			(end 0.925 -0.47)
			(stroke
				(width 0.05)
				(type default)
			)
			(fill no)
			(layer "B.CrtYd")
		)
		(fp_line
			(start 0.504 -0.248)
			(end -0.494 -0.248)
			(stroke
				(width 0.15)
				(type solid)
			)
			(layer "B.Fab")
		)
		(fp_line
			(start -0.494 -0.248)
			(end -0.494 0.25)
			(stroke
				(width 0.15)
				(type solid)
			)
			(layer "B.Fab")
		)
		(fp_line
			(start 0.504 0.25)
			(end 0.504 -0.248)
			(stroke
				(width 0.15)
				(type solid)
			)
			(layer "B.Fab")
		)
		(fp_line
			(start -0.494 0.25)
			(end 0.504 0.25)
			(stroke
				(width 0.15)
				(type solid)
			)
			(layer "B.Fab")
		)
		(fp_text user "${REFERENCE}"
			(at -0.939 -4.599 270)
			(layer "B.Fab")
			(effects
				(font
					(size 0.7 0.7)
					(thickness 0.15)
				)
				(justify left bottom mirror)
			)
		)
		(fp_text user "Author: Antmicro"
			(at -0.939 -3.399 270)
			(layer "B.Fab")
			(effects
				(font
					(size 0.7 0.7)
					(thickness 0.15)
				)
				(justify left bottom mirror)
			)
		)
		(fp_text user "License: Apache-2.0"
			(at -0.939 -5.799 270)
			(layer "B.Fab")
			(effects
				(font
					(size 0.7 0.7)
					(thickness 0.15)
				)
				(justify left bottom mirror)
			)
		)
		(pad "1" smd roundrect
			(at -0.48 0 90)
			(size 0.59 0.64)
			(layers "B.Cu" "B.Mask" "B.Paste")
			(roundrect_rratio 0.25)
			(net 226 "/Supply/DC-DC VCCINT/V_{0SNS+}")
			(pintype "passive")
		)
		(pad "2" smd roundrect
			(at 0.48 0 90)
			(size 0.59 0.64)
			(layers "B.Cu" "B.Mask" "B.Paste")
			(roundrect_rratio 0.25)
			(net 756 "Net-(C264-Pad2)")
			(pintype "passive")
		)
	)
	(footprint "antmicro-footprints:C_0402_1005Metric"
		(layer "B.Cu")
		(at 172.65 193.299501 90)
		(descr "Capacitor SMD 0402")
		(tags "capacitor SMD 0402")
		(property "Reference" "C231"
			(at 0.994 0.403501 90)
			(layer "B.SilkS")
			(effects
				(font
					(size 0.7 0.7)
					(thickness 0.15)
				)
				(justify right bottom mirror)
			)
		)
		(property "Value" "C_100n_0402"
			(at -1.022927 -2.155213 90)
			(layer "B.Fab")
			(effects
				(font
					(size 0.7 0.7)
					(thickness 0.15)
				)
				(justify right bottom mirror)
			)
		)
		(property "Datasheet" "https://www.murata.com/products/productdetail?partno=GRM155R61H104KE14%23"
			(at 0 0 90)
			(layer "F.Fab")
			(hide yes)
			(effects
				(font
					(size 1.27 1.27)
					(thickness 0.15)
				)
			)
		)
		(property "Manufacturer" "Murata"
			(at 0 0 90)
			(unlocked yes)
			(layer "B.Fab")
			(hide yes)
			(effects
				(font
					(size 1 1)
					(thickness 0.15)
				)
				(justify mirror)
			)
		)
		(property "MPN" "GRM155R61H104KE14D"
			(at 0 0 90)
			(unlocked yes)
			(layer "B.Fab")
			(hide yes)
			(effects
				(font
					(size 1 1)
					(thickness 0.15)
				)
				(justify mirror)
			)
		)
		(property "Val" "100n"
			(at 0 0 90)
			(unlocked yes)
			(layer "B.Fab")
			(hide yes)
			(effects
				(font
					(size 1 1)
					(thickness 0.15)
				)
				(justify mirror)
			)
		)
		(property "License" "Apache-2.0"
			(at 0 0 90)
			(unlocked yes)
			(layer "B.Fab")
			(hide yes)
			(effects
				(font
					(size 1 1)
					(thickness 0.15)
				)
				(justify mirror)
			)
		)
		(property "Author" "Antmicro"
			(at 0 0 90)
			(unlocked yes)
			(layer "B.Fab")
			(hide yes)
			(effects
				(font
					(size 1 1)
					(thickness 0.15)
				)
				(justify mirror)
			)
		)
		(property "Voltage" "50V"
			(at 0 0 90)
			(unlocked yes)
			(layer "B.Fab")
			(hide yes)
			(effects
				(font
					(size 1 1)
					(thickness 0.15)
				)
				(justify mirror)
			)
		)
		(property "Dielectric" "X5R"
			(at 0 0 90)
			(unlocked yes)
			(layer "B.Fab")
			(hide yes)
			(effects
				(font
					(size 1 1)
					(thickness 0.15)
				)
				(justify mirror)
			)
		)
		(sheetname "/FPGA MGT Interface/")
		(sheetfile "fpga-mgt.kicad_sch")
		(attr smd)
		(fp_rect
			(start -0.925 0.47)
			(end 0.925 -0.47)
			(stroke
				(width 0.05)
				(type default)
			)
			(fill no)
			(layer "B.CrtYd")
		)
		(fp_line
			(start 0.504 -0.248)
			(end -0.494 -0.248)
			(stroke
				(width 0.15)
				(type solid)
			)
			(layer "B.Fab")
		)
		(fp_line
			(start -0.494 -0.248)
			(end -0.494 0.25)
			(stroke
				(width 0.15)
				(type solid)
			)
			(layer "B.Fab")
		)
		(fp_line
			(start 0.504 0.25)
			(end 0.504 -0.248)
			(stroke
				(width 0.15)
				(type solid)
			)
			(layer "B.Fab")
		)
		(fp_line
			(start -0.494 0.25)
			(end 0.504 0.25)
			(stroke
				(width 0.15)
				(type solid)
			)
			(layer "B.Fab")
		)
		(fp_text user "Author: Antmicro"
			(at -0.939 -3.399 270)
			(layer "B.Fab")
			(effects
				(font
					(size 0.7 0.7)
					(thickness 0.15)
				)
				(justify left bottom mirror)
			)
		)
		(fp_text user "License: Apache-2.0"
			(at -0.939 -5.799 270)
			(layer "B.Fab")
			(effects
				(font
					(size 0.7 0.7)
					(thickness 0.15)
				)
				(justify left bottom mirror)
			)
		)
		(fp_text user "${REFERENCE}"
			(at -0.939 -4.599 270)
			(layer "B.Fab")
			(effects
				(font
					(size 0.7 0.7)
					(thickness 0.15)
				)
				(justify left bottom mirror)
			)
		)
		(pad "1" smd roundrect
			(at -0.48 0 90)
			(size 0.59 0.64)
			(layers "B.Cu" "B.Mask" "B.Paste")
			(roundrect_rratio 0.25)
			(net 25 "/FPGA MGT Interface/PCIE.TXD2_N")
			(pintype "passive")
		)
		(pad "2" smd roundrect
			(at 0.48 0 90)
			(size 0.59 0.64)
			(layers "B.Cu" "B.Mask" "B.Paste")
			(roundrect_rratio 0.25)
			(net 26 "/FPGA MGT Interface/GTY_225_TX1_N")
			(pintype "passive")
		)
	)
	(footprint "antmicro-footprints:C_0603_1608Metric"
		(layer "B.Cu")
		(at 253.7 104.325 90)
		(descr "Capacitor SMD 0603")
		(tags "capacitor 0603")
		(property "Reference" "C319"
			(at -4.075 0.5 90)
			(layer "B.SilkS")
			(effects
				(font
					(size 0.7 0.7)
					(thickness 0.15)
				)
				(justify right bottom mirror)
			)
		)
		(property "Value" "C_10u_25V_0603"
			(at -1.42757 -1.770288 90)
			(layer "B.Fab")
			(effects
				(font
					(size 0.7 0.7)
					(thickness 0.15)
				)
				(justify right bottom mirror)
			)
		)
		(property "Datasheet" "https://product.tdk.com/en/search/capacitor/ceramic/mlcc/info?part_no=C1608X5R1E106M080AC"
			(at 0 0 90)
			(layer "B.Fab")
			(hide yes)
			(effects
				(font
					(size 1.27 1.27)
					(thickness 0.15)
				)
				(justify mirror)
			)
		)
		(property "MPN" "C1608X5R1E106M080AC"
			(at 0 0 90)
			(unlocked yes)
			(layer "B.Fab")
			(hide yes)
			(effects
				(font
					(size 1 1)
					(thickness 0.15)
				)
				(justify mirror)
			)
		)
		(property "Manufacturer" "TDK"
			(at 0 0 90)
			(unlocked yes)
			(layer "B.Fab")
			(hide yes)
			(effects
				(font
					(size 1 1)
					(thickness 0.15)
				)
				(justify mirror)
			)
		)
		(property "License" "Apache-2.0"
			(at 0 0 90)
			(unlocked yes)
			(layer "B.Fab")
			(hide yes)
			(effects
				(font
					(size 1 1)
					(thickness 0.15)
				)
				(justify mirror)
			)
		)
		(property "Author" "Antmicro"
			(at 0 0 90)
			(unlocked yes)
			(layer "B.Fab")
			(hide yes)
			(effects
				(font
					(size 1 1)
					(thickness 0.15)
				)
				(justify mirror)
			)
		)
		(property "Val" "10u"
			(at 0 0 90)
			(unlocked yes)
			(layer "B.Fab")
			(hide yes)
			(effects
				(font
					(size 1 1)
					(thickness 0.15)
				)
				(justify mirror)
			)
		)
		(property "Voltage" "25V"
			(at 0 0 90)
			(unlocked yes)
			(layer "B.Fab")
			(hide yes)
			(effects
				(font
					(size 1 1)
					(thickness 0.15)
				)
				(justify mirror)
			)
		)
		(property "Dielectric" ""
			(at 0 0 90)
			(unlocked yes)
			(layer "B.Fab")
			(hide yes)
			(effects
				(font
					(size 1 1)
					(thickness 0.15)
				)
				(justify mirror)
			)
		)
		(sheetname "/DDR5 RDIMM/")
		(sheetfile "ddr5-rdimm.kicad_sch")
		(attr smd)
		(fp_line
			(start -0.15 -0.4)
			(end 0.15 -0.4)
			(stroke
				(width 0.15)
				(type solid)
			)
			(layer "B.SilkS")
		)
		(fp_line
			(start -0.15 0.4)
			(end 0.15 0.4)
			(stroke
				(width 0.15)
				(type solid)
			)
			(layer "B.SilkS")
		)
		(fp_rect
			(start -1.25 0.65)
			(end 1.25 -0.65)
			(stroke
				(width 0.05)
				(type solid)
			)
			(fill no)
			(layer "B.CrtYd")
		)
		(fp_rect
			(start -0.8 0.4)
			(end 0.8 -0.4)
			(stroke
				(width 0.15)
				(type solid)
			)
			(fill no)
			(layer "B.Fab")
		)
		(fp_text user "Author: Antmicro"
			(at -1.682 -4.894 270)
			(layer "B.Fab")
			(effects
				(font
					(size 0.7 0.7)
					(thickness 0.15)
				)
				(justify left bottom mirror)
			)
		)
		(fp_text user "License: Apache-2.0"
			(at -1.682 -5.895 270)
			(layer "B.Fab")
			(effects
				(font
					(size 0.7 0.7)
					(thickness 0.15)
				)
				(justify left bottom mirror)
			)
		)
		(fp_text user "${REFERENCE}"
			(at -1.682 -3.895 270)
			(layer "B.Fab")
			(effects
				(font
					(size 0.7 0.7)
					(thickness 0.15)
				)
				(justify left bottom mirror)
			)
		)
		(pad "1" smd roundrect
			(at -0.7 0 90)
			(size 0.8 1)
			(layers "B.Cu" "B.Mask" "B.Paste")
			(roundrect_rratio 0.2)
			(net 1 "GND")
			(pintype "passive")
		)
		(pad "2" smd roundrect
			(at 0.7 0 90)
			(size 0.8 1)
			(layers "B.Cu" "B.Mask" "B.Paste")
			(roundrect_rratio 0.2)
			(net 803 "/DDR5 RDIMM/VIN_MGMT")
			(pintype "passive")
		)
	)
	(footprint "antmicro-footprints:C_0402_1005Metric_EIA"
		(layer "B.Cu")
		(at 196.502 159)
		(descr "Capacitor SMD 0402 (1005 Metric), square (rectangular) end terminal, IPC_7351 nominal, (Body size source: IPC-SM-782 page 76, https://www.pcb-3d.com/wordpress/wp-content/uploads/ipc-sm-782a_amendment_1_and_2.pdf)")
		(tags "capacitor 0402")
		(property "Reference" "C98"
			(at -31.927 -10.3 0)
			(layer "B.SilkS")
			(effects
				(font
					(size 0.7 0.7)
					(thickness 0.15)
				)
				(justify right bottom mirror)
			)
		)
		(property "Value" "C_100n_0402"
			(at 0 -1.169 0)
			(layer "B.Fab")
			(effects
				(font
					(size 0.7 0.7)
					(thickness 0.15)
				)
				(justify right bottom mirror)
			)
		)
		(property "Datasheet" "https://www.murata.com/products/productdetail?partno=GRM155R61H104KE14%23"
			(at 0 0 0)
			(layer "F.Fab")
			(hide yes)
			(effects
				(font
					(size 1.27 1.27)
					(thickness 0.15)
				)
			)
		)
		(property "MPN" "GRM155R61H104KE14D"
			(at 0 0 0)
			(unlocked yes)
			(layer "B.Fab")
			(hide yes)
			(effects
				(font
					(size 1 1)
					(thickness 0.15)
				)
				(justify mirror)
			)
		)
		(property "Manufacturer" "Murata"
			(at 0 0 0)
			(unlocked yes)
			(layer "B.Fab")
			(hide yes)
			(effects
				(font
					(size 1 1)
					(thickness 0.15)
				)
				(justify mirror)
			)
		)
		(property "License" "Apache-2.0"
			(at 0 0 0)
			(unlocked yes)
			(layer "B.Fab")
			(hide yes)
			(effects
				(font
					(size 1 1)
					(thickness 0.15)
				)
				(justify mirror)
			)
		)
		(property "Author" "Antmicro"
			(at 0 0 0)
			(unlocked yes)
			(layer "B.Fab")
			(hide yes)
			(effects
				(font
					(size 1 1)
					(thickness 0.15)
				)
				(justify mirror)
			)
		)
		(property "Val" "100n"
			(at 0 0 0)
			(unlocked yes)
			(layer "B.Fab")
			(hide yes)
			(effects
				(font
					(size 1 1)
					(thickness 0.15)
				)
				(justify mirror)
			)
		)
		(property "Voltage" "50V"
			(at 0 0 0)
			(unlocked yes)
			(layer "B.Fab")
			(hide yes)
			(effects
				(font
					(size 1 1)
					(thickness 0.15)
				)
				(justify mirror)
			)
		)
		(property "Dielectric" "X5R"
			(at 0 0 0)
			(unlocked yes)
			(layer "B.Fab")
			(hide yes)
			(effects
				(font
					(size 1 1)
					(thickness 0.15)
				)
				(justify mirror)
			)
		)
		(sheetname "/FPGA power/")
		(sheetfile "fpga-power.kicad_sch")
		(attr smd)
		(fp_rect
			(start -0.95 0.45)
			(end 0.95 -0.45)
			(stroke
				(width 0.05)
				(type default)
			)
			(fill no)
			(layer "B.CrtYd")
		)
		(fp_line
			(start -0.5 -0.248)
			(end -0.5 0.25)
			(stroke
				(width 0.15)
				(type solid)
			)
			(layer "B.Fab")
		)
		(fp_line
			(start -0.5 0.25)
			(end 0.498 0.25)
			(stroke
				(width 0.15)
				(type solid)
			)
			(layer "B.Fab")
		)
		(fp_line
			(start 0.498 -0.248)
			(end -0.5 -0.248)
			(stroke
				(width 0.15)
				(type solid)
			)
			(layer "B.Fab")
		)
		(fp_line
			(start 0.498 0.25)
			(end 0.498 -0.248)
			(stroke
				(width 0.15)
				(type solid)
			)
			(layer "B.Fab")
		)
		(fp_text user "License: Apache-2.0"
			(at -0.9656 -4.369 180)
			(layer "B.Fab")
			(effects
				(font
					(size 0.7 0.7)
					(thickness 0.15)
				)
				(justify left bottom mirror)
			)
		)
		(fp_text user "Author: Antmicro"
			(at -0.9656 -5.569 180)
			(layer "B.Fab")
			(effects
				(font
					(size 0.7 0.7)
					(thickness 0.15)
				)
				(justify left bottom mirror)
			)
		)
		(fp_text user "${REFERENCE}"
			(at -0.9656 -3.169 180)
			(layer "B.Fab")
			(effects
				(font
					(size 0.7 0.7)
					(thickness 0.15)
				)
				(justify left bottom mirror)
			)
		)
		(pad "1" smd roundrect
			(at -0.5 0 270)
			(size 0.6 0.6)
			(layers "B.Cu" "B.Mask" "B.Paste")
			(roundrect_rratio 0.25)
			(net 1 "GND")
			(pintype "passive")
		)
		(pad "2" smd roundrect
			(at 0.498 0)
			(size 0.6 0.6)
			(layers "B.Cu" "B.Mask" "B.Paste")
			(roundrect_rratio 0.25)
			(net 820 "+0V9_MGTAVCC")
			(pintype "passive")
		)
	)
	(footprint "antmicro-footprints:C_0603_1608Metric"
		(layer "B.Cu")
		(at 228.784999 172.080002 90)
		(descr "Capacitor SMD 0603")
		(tags "capacitor 0603")
		(property "Reference" "C263"
			(at -4.069998 0.320001 90)
			(layer "B.SilkS")
			(effects
				(font
					(size 0.7 0.7)
					(thickness 0.15)
				)
				(justify right bottom mirror)
			)
		)
		(property "Value" "C_22u_0603"
			(at -1.42757 -1.770288 90)
			(layer "B.Fab")
			(effects
				(font
					(size 0.7 0.7)
					(thickness 0.15)
				)
				(justify right bottom mirror)
			)
		)
		(property "Datasheet" "https://www.murata.com/products/productdetail?partno=GRM188R60J226MEA0%23"
			(at 0 0 90)
			(layer "F.Fab")
			(hide yes)
			(effects
				(font
					(size 1.27 1.27)
					(thickness 0.15)
				)
			)
		)
		(property "Manufacturer" "Murata"
			(at 0 0 90)
			(unlocked yes)
			(layer "B.Fab")
			(hide yes)
			(effects
				(font
					(size 1 1)
					(thickness 0.15)
				)
				(justify mirror)
			)
		)
		(property "MPN" "GRM188R60J226MEA0D"
			(at 0 0 90)
			(unlocked yes)
			(layer "B.Fab")
			(hide yes)
			(effects
				(font
					(size 1 1)
					(thickness 0.15)
				)
				(justify mirror)
			)
		)
		(property "Val" "22u"
			(at 0 0 90)
			(unlocked yes)
			(layer "B.Fab")
			(hide yes)
			(effects
				(font
					(size 1 1)
					(thickness 0.15)
				)
				(justify mirror)
			)
		)
		(property "License" "Apache-2.0"
			(at 0 0 90)
			(unlocked yes)
			(layer "B.Fab")
			(hide yes)
			(effects
				(font
					(size 1 1)
					(thickness 0.15)
				)
				(justify mirror)
			)
		)
		(property "Author" "Antmicro"
			(at 0 0 90)
			(unlocked yes)
			(layer "B.Fab")
			(hide yes)
			(effects
				(font
					(size 1 1)
					(thickness 0.15)
				)
				(justify mirror)
			)
		)
		(property "Voltage" ""
			(at 0 0 90)
			(unlocked yes)
			(layer "B.Fab")
			(hide yes)
			(effects
				(font
					(size 1 1)
					(thickness 0.15)
				)
				(justify mirror)
			)
		)
		(property "Dielectric" ""
			(at 0 0 90)
			(unlocked yes)
			(layer "B.Fab")
			(hide yes)
			(effects
				(font
					(size 1 1)
					(thickness 0.15)
				)
				(justify mirror)
			)
		)
		(sheetname "/Supply/DC-DC VCCINT/")
		(sheetfile "dc-dc-vccint.kicad_sch")
		(attr smd)
		(fp_line
			(start -0.15 -0.4)
			(end 0.15 -0.4)
			(stroke
				(width 0.15)
				(type solid)
			)
			(layer "B.SilkS")
		)
		(fp_line
			(start -0.15 0.4)
			(end 0.15 0.4)
			(stroke
				(width 0.15)
				(type solid)
			)
			(layer "B.SilkS")
		)
		(fp_rect
			(start -1.25 0.65)
			(end 1.25 -0.65)
			(stroke
				(width 0.05)
				(type solid)
			)
			(fill no)
			(layer "B.CrtYd")
		)
		(fp_rect
			(start -0.8 0.4)
			(end 0.8 -0.4)
			(stroke
				(width 0.15)
				(type solid)
			)
			(fill no)
			(layer "B.Fab")
		)
		(fp_text user "Author: Antmicro"
			(at -1.682 -4.894 270)
			(layer "B.Fab")
			(effects
				(font
					(size 0.7 0.7)
					(thickness 0.15)
				)
				(justify left bottom mirror)
			)
		)
		(fp_text user "${REFERENCE}"
			(at -1.682 -3.895 270)
			(layer "B.Fab")
			(effects
				(font
					(size 0.7 0.7)
					(thickness 0.15)
				)
				(justify left bottom mirror)
			)
		)
		(fp_text user "License: Apache-2.0"
			(at -1.682 -5.895 270)
			(layer "B.Fab")
			(effects
				(font
					(size 0.7 0.7)
					(thickness 0.15)
				)
				(justify left bottom mirror)
			)
		)
		(pad "1" smd roundrect
			(at -0.7 0 90)
			(size 0.8 1)
			(layers "B.Cu" "B.Mask" "B.Paste")
			(roundrect_rratio 0.2)
			(net 1 "GND")
			(pintype "passive")
		)
		(pad "2" smd roundrect
			(at 0.7 0 90)
			(size 0.8 1)
			(layers "B.Cu" "B.Mask" "B.Paste")
			(roundrect_rratio 0.2)
			(net 224 "/Supply/DC-DC VCCINT/0V85_REG1")
			(pintype "passive")
		)
	)
)
